(kicad_pcb
	(version 20260206)
	(generator "pcbnew")
	(generator_version "10.0")
	(general
		(thickness 1.6)
		(legacy_teardrops no)
	)
	(paper "A4")
	(title_block
		(title "peb — Lightning_PEB_BRD.brd")
		(comment 1 "Lightning (Wiwynn / Facebook NVMe JBOF) / footprints 593-600 of 2563")
	)
	(layers
		(0 "F.Cu" signal "TOP")
		(4 "In1.Cu" signal "L2GND")
		(6 "In2.Cu" signal "L3")
		(8 "In3.Cu" signal "L4VCC")
		(10 "In4.Cu" signal "L5VCC")
		(12 "In5.Cu" signal "L6")
		(14 "In6.Cu" signal "L7GND")
		(2 "B.Cu" signal "BOTTOM")
		(9 "F.Adhes" user "F.Adhesive")
		(11 "B.Adhes" user "B.Adhesive")
		(13 "F.Paste" user "Package Geometry/Pastemask Top")
		(15 "B.Paste" user "Package Geometry/Pastemask Bottom")
		(5 "F.SilkS" user "Ref Des/Silkscreen Top")
		(7 "B.SilkS" user "Ref Des/Silkscreen Bottom")
		(1 "F.Mask" user "Board Geometry/Soldermask Top")
		(3 "B.Mask" user "Board Geometry/Soldermask Bottom")
		(17 "Dwgs.User" user "User.Drawings")
		(19 "Cmts.User" user "User.Comments")
		(21 "Eco1.User" user "User.Eco1")
		(23 "Eco2.User" user "User.Eco2")
		(25 "Edge.Cuts" user "Board Geometry/Outline")
		(27 "Margin" user)
		(31 "F.CrtYd" user "Package Geometry/Place Bound Top")
		(29 "B.CrtYd" user "Package Geometry/Place Bound Bottom")
		(35 "F.Fab" user "Ref Des/Assembly Top")
		(33 "B.Fab" user "Ref Des/Assembly Bottom")
	)
	(footprint ""
		(layer "F.Cu")
		(at 239.395 -23.241 180)
		(property "Reference" "R781"
			(at 0 0 180)
			(layer "F.SilkS")
			(hide yes)
			(effects
				(font
					(size 1.27 1.27)
				)
			)
		)
		(property "Value" "4K7R2F-GP"
			(at 0.064008 -3.993896 180)
			(unlocked yes)
			(layer "F.Fab")
			(hide yes)
			(effects
				(font
					(size 1.016 1.016)
					(thickness 0.1524)
				)
			)
		)
		(property "Device Type" "R402H16"
			(at 0.064008 -5.517896 180)
			(unlocked yes)
			(layer "F.Fab")
			(hide yes)
			(effects
				(font
					(size 1.016 1.016)
					(thickness 0.1524)
				)
			)
		)
		(duplicate_pad_numbers_are_jumpers no)
		(fp_line
			(start 0.508 -0.9398)
			(end -0.508 -0.9398)
			(stroke
				(width 0.1524)
				(type default)
			)
			(layer "F.SilkS")
		)
		(fp_line
			(start -0.508 -0.9398)
			(end -0.508 0.9398)
			(stroke
				(width 0.1524)
				(type default)
			)
			(layer "F.SilkS")
		)
		(fp_rect
			(start -0.508 0.9398)
			(end 0.508 -0.9398)
			(stroke
				(width 0)
				(type default)
			)
			(fill no)
			(layer "F.CrtYd")
		)
		(fp_rect
			(start -0.508 0.9398)
			(end 0.508 -0.9398)
			(stroke
				(width 0)
				(type default)
			)
			(fill no)
			(layer "F.Fab")
		)
		(pad "1" smd custom
			(at 0 -0.4445 180)
			(size 0.1397 0.1397)
			(layers "F.Cu" "F.Mask" "F.Paste")
			(net "BOOTSTRAP1")
			(options
				(clearance outline)
				(anchor circle)
			)
			(primitives
				(gr_poly
					(pts
						(arc
							(start -0.1778 -0.2794)
							(mid -0.249642 -0.249642)
							(end -0.2794 -0.1778)
						)
						(arc
							(start -0.2794 0.1778)
							(mid -0.249642 0.249642)
							(end -0.1778 0.2794)
						)
						(arc
							(start 0.1778 0.2794)
							(mid 0.249642 0.249642)
							(end 0.2794 0.1778)
						)
						(arc
							(start 0.2794 -0.1778)
							(mid 0.249642 -0.249642)
							(end 0.1778 -0.2794)
						)
					)
					(width 0)
					(fill yes)
				)
			)
		)
		(pad "2" smd custom
			(at 0 0.4445 180)
			(size 0.1397 0.1397)
			(layers "F.Cu" "F.Mask" "F.Paste")
			(net "BOOTSTRAP_R_1")
			(options
				(clearance outline)
				(anchor circle)
			)
			(primitives
				(gr_poly
					(pts
						(arc
							(start -0.1778 -0.2794)
							(mid -0.249642 -0.249642)
							(end -0.2794 -0.1778)
						)
						(arc
							(start -0.2794 0.1778)
							(mid -0.249642 0.249642)
							(end -0.1778 0.2794)
						)
						(arc
							(start 0.1778 0.2794)
							(mid 0.249642 0.249642)
							(end 0.2794 0.1778)
						)
						(arc
							(start 0.2794 -0.1778)
							(mid 0.249642 -0.249642)
							(end 0.1778 -0.2794)
						)
					)
					(width 0)
					(fill yes)
				)
			)
		)
	)
	(footprint ""
		(layer "F.Cu")
		(at 28.079954 -162.162744 90)
		(property "Reference" "C272"
			(at 0 0 90)
			(layer "F.SilkS")
			(hide yes)
			(effects
				(font
					(size 1.27 1.27)
				)
			)
		)
		(property "Value" "SCD1U16V2KX-3GP"
			(at 1.1811 -2.7051 90)
			(unlocked yes)
			(layer "F.Fab")
			(hide yes)
			(effects
				(font
					(size 1.016 1.016)
					(thickness 0.1524)
				)
			)
		)
		(property "Device Type" "C402H22"
			(at 1.1811 -4.2291 90)
			(unlocked yes)
			(layer "F.Fab")
			(hide yes)
			(effects
				(font
					(size 1.016 1.016)
					(thickness 0.1524)
				)
			)
		)
		(duplicate_pad_numbers_are_jumpers no)
		(fp_rect
			(start -0.4318 0.9525)
			(end 0.4318 -0.9525)
			(stroke
				(width 0)
				(type default)
			)
			(fill no)
			(layer "F.CrtYd")
		)
		(fp_rect
			(start -0.4318 0.9525)
			(end 0.4318 -0.9525)
			(stroke
				(width 0)
				(type default)
			)
			(fill no)
			(layer "F.Fab")
		)
		(pad "1" smd custom
			(at 0 -0.4445 90)
			(size 0.1524 0.1524)
			(layers "F.Cu" "F.Mask" "F.Paste")
			(net "P3V3_STBY")
			(options
				(clearance outline)
				(anchor circle)
			)
			(primitives
				(gr_poly
					(pts
						(arc
							(start 0.3048 -0.2032)
							(mid 0.275042 -0.275042)
							(end 0.2032 -0.3048)
						)
						(arc
							(start -0.2032 -0.3048)
							(mid -0.275042 -0.275042)
							(end -0.3048 -0.2032)
						)
						(arc
							(start -0.3048 0.2032)
							(mid -0.275042 0.275042)
							(end -0.2032 0.3048)
						)
						(arc
							(start 0.2032 0.3048)
							(mid 0.275042 0.275042)
							(end 0.3048 0.2032)
						)
					)
					(width 0)
					(fill yes)
				)
			)
		)
		(pad "2" smd custom
			(at 0 0.4445 90)
			(size 0.1524 0.1524)
			(layers "F.Cu" "F.Mask" "F.Paste")
			(net "GND")
			(options
				(clearance outline)
				(anchor circle)
			)
			(primitives
				(gr_poly
					(pts
						(arc
							(start 0.3048 -0.2032)
							(mid 0.275042 -0.275042)
							(end 0.2032 -0.3048)
						)
						(arc
							(start -0.2032 -0.3048)
							(mid -0.275042 -0.275042)
							(end -0.3048 -0.2032)
						)
						(arc
							(start -0.3048 0.2032)
							(mid -0.275042 0.275042)
							(end -0.2032 0.3048)
						)
						(arc
							(start 0.2032 0.3048)
							(mid 0.275042 0.275042)
							(end 0.3048 0.2032)
						)
					)
					(width 0)
					(fill yes)
				)
			)
		)
	)
	(footprint ""
		(layer "F.Cu")
		(at 75.983592 -195.73367 180)
		(property "Reference" "R7931"
			(at 0 0 180)
			(layer "F.SilkS")
			(hide yes)
			(effects
				(font
					(size 1.27 1.27)
				)
			)
		)
		(property "Value" "0R2J-2-GP"
			(at 0.064008 -3.993896 180)
			(unlocked yes)
			(layer "F.Fab")
			(hide yes)
			(effects
				(font
					(size 1.016 1.016)
					(thickness 0.1524)
				)
			)
		)
		(property "Device Type" "R402H16"
			(at 0.064008 -5.517896 180)
			(unlocked yes)
			(layer "F.Fab")
			(hide yes)
			(effects
				(font
					(size 1.016 1.016)
					(thickness 0.1524)
				)
			)
		)
		(duplicate_pad_numbers_are_jumpers no)
		(fp_line
			(start 0.508 -0.9398)
			(end -0.508 -0.9398)
			(stroke
				(width 0.1524)
				(type default)
			)
			(layer "F.SilkS")
		)
		(fp_line
			(start -0.508 -0.9398)
			(end -0.508 0.9398)
			(stroke
				(width 0.1524)
				(type default)
			)
			(layer "F.SilkS")
		)
		(fp_rect
			(start -0.508 0.9398)
			(end 0.508 -0.9398)
			(stroke
				(width 0)
				(type default)
			)
			(fill no)
			(layer "F.CrtYd")
		)
		(fp_rect
			(start -0.508 0.9398)
			(end 0.508 -0.9398)
			(stroke
				(width 0)
				(type default)
			)
			(fill no)
			(layer "F.Fab")
		)
		(pad "1" smd custom
			(at 0 -0.4445 180)
			(size 0.1397 0.1397)
			(layers "F.Cu" "F.Mask" "F.Paste")
			(net "SSD_PRSNT#11")
			(options
				(clearance outline)
				(anchor circle)
			)
			(primitives
				(gr_poly
					(pts
						(arc
							(start -0.1778 -0.2794)
							(mid -0.249642 -0.249642)
							(end -0.2794 -0.1778)
						)
						(arc
							(start -0.2794 0.1778)
							(mid -0.249642 0.249642)
							(end -0.1778 0.2794)
						)
						(arc
							(start 0.1778 0.2794)
							(mid 0.249642 0.249642)
							(end 0.2794 0.1778)
						)
						(arc
							(start 0.2794 -0.1778)
							(mid 0.249642 -0.249642)
							(end 0.1778 -0.2794)
						)
					)
					(width 0)
					(fill yes)
				)
			)
		)
		(pad "2" smd custom
			(at 0 0.4445 180)
			(size 0.1397 0.1397)
			(layers "F.Cu" "F.Mask" "F.Paste")
			(net "SSD_PRSNT#11_R")
			(options
				(clearance outline)
				(anchor circle)
			)
			(primitives
				(gr_poly
					(pts
						(arc
							(start -0.1778 -0.2794)
							(mid -0.249642 -0.249642)
							(end -0.2794 -0.1778)
						)
						(arc
							(start -0.2794 0.1778)
							(mid -0.249642 0.249642)
							(end -0.1778 0.2794)
						)
						(arc
							(start 0.1778 0.2794)
							(mid 0.249642 0.249642)
							(end 0.2794 0.1778)
						)
						(arc
							(start 0.2794 -0.1778)
							(mid 0.249642 -0.249642)
							(end 0.1778 -0.2794)
						)
					)
					(width 0)
					(fill yes)
				)
			)
		)
	)
	(footprint ""
		(layer "F.Cu")
		(at 52.197 -185.293 -90)
		(property "Reference" "R898"
			(at 0 0 270)
			(layer "F.SilkS")
			(hide yes)
			(effects
				(font
					(size 1.27 1.27)
				)
			)
		)
		(property "Value" "4K7R2J-2-GP"
			(at 0.064008 -3.993896 270)
			(unlocked yes)
			(layer "F.Fab")
			(hide yes)
			(effects
				(font
					(size 1.016 1.016)
					(thickness 0.1524)
				)
			)
		)
		(property "Device Type" "R402H16"
			(at 0.064008 -5.517896 270)
			(unlocked yes)
			(layer "F.Fab")
			(hide yes)
			(effects
				(font
					(size 1.016 1.016)
					(thickness 0.1524)
				)
			)
		)
		(duplicate_pad_numbers_are_jumpers no)
		(fp_line
			(start -0.508 -0.9398)
			(end -0.508 0.9398)
			(stroke
				(width 0.1524)
				(type default)
			)
			(layer "F.SilkS")
		)
		(fp_line
			(start 0.508 -0.9398)
			(end -0.508 -0.9398)
			(stroke
				(width 0.1524)
				(type default)
			)
			(layer "F.SilkS")
		)
		(fp_rect
			(start -0.508 0.9398)
			(end 0.508 -0.9398)
			(stroke
				(width 0)
				(type default)
			)
			(fill no)
			(layer "F.CrtYd")
		)
		(fp_rect
			(start -0.508 0.9398)
			(end 0.508 -0.9398)
			(stroke
				(width 0)
				(type default)
			)
			(fill no)
			(layer "F.Fab")
		)
		(pad "1" smd custom
			(at 0 -0.4445 270)
			(size 0.1397 0.1397)
			(layers "F.Cu" "F.Mask" "F.Paste")
			(net "P3V3_STBY")
			(options
				(clearance outline)
				(anchor circle)
			)
			(primitives
				(gr_poly
					(pts
						(arc
							(start -0.1778 -0.2794)
							(mid -0.249642 -0.249642)
							(end -0.2794 -0.1778)
						)
						(arc
							(start -0.2794 0.1778)
							(mid -0.249642 0.249642)
							(end -0.1778 0.2794)
						)
						(arc
							(start 0.1778 0.2794)
							(mid 0.249642 0.249642)
							(end 0.2794 0.1778)
						)
						(arc
							(start 0.2794 -0.1778)
							(mid 0.249642 -0.249642)
							(end 0.1778 -0.2794)
						)
					)
					(width 0)
					(fill yes)
				)
			)
		)
		(pad "2" smd custom
			(at 0 0.4445 270)
			(size 0.1397 0.1397)
			(layers "F.Cu" "F.Mask" "F.Paste")
			(net "BUF_I2C8_CLKBUF1_SCL_R")
			(options
				(clearance outline)
				(anchor circle)
			)
			(primitives
				(gr_poly
					(pts
						(arc
							(start -0.1778 -0.2794)
							(mid -0.249642 -0.249642)
							(end -0.2794 -0.1778)
						)
						(arc
							(start -0.2794 0.1778)
							(mid -0.249642 0.249642)
							(end -0.1778 0.2794)
						)
						(arc
							(start 0.1778 0.2794)
							(mid 0.249642 0.249642)
							(end 0.2794 0.1778)
						)
						(arc
							(start 0.2794 -0.1778)
							(mid 0.249642 -0.249642)
							(end 0.1778 -0.2794)
						)
					)
					(width 0)
					(fill yes)
				)
			)
		)
	)
	(footprint ""
		(layer "F.Cu")
		(at 301.244 -57.0992)
		(property "Reference" "C426"
			(at 0 0 0)
			(layer "F.SilkS")
			(hide yes)
			(effects
				(font
					(size 1.27 1.27)
				)
			)
		)
		(property "Value" "SC10U16V5KX-1-GP"
			(at -0.0762 -6.1214 0)
			(unlocked yes)
			(layer "F.Fab")
			(hide yes)
			(effects
				(font
					(size 1.016 1.016)
					(thickness 0.1524)
				)
			)
		)
		(property "Device Type" "C805H54"
			(at -0.0762 -8.1534 0)
			(unlocked yes)
			(layer "F.Fab")
			(hide yes)
			(effects
				(font
					(size 1.016 1.016)
					(thickness 0.1524)
				)
			)
		)
		(duplicate_pad_numbers_are_jumpers no)
		(fp_line
			(start 0.635 0)
			(end -0.635 0)
			(stroke
				(width 0.508)
				(type default)
			)
			(layer "F.SilkS")
		)
		(fp_rect
			(start -0.9652 1.778)
			(end 0.9652 -1.778)
			(stroke
				(width 0)
				(type default)
			)
			(fill no)
			(layer "F.CrtYd")
		)
		(fp_poly
			(pts
				(xy -0.9652 -1.778) (xy 0.9652 -1.778) (xy 0.9652 1.778) (xy -0.9652 1.778)
			)
			(stroke
				(width 0)
				(type default)
			)
			(fill no)
			(layer "F.Fab")
		)
		(pad "1" smd rect
			(at 0 -0.9652)
			(size 1.397 1.143)
			(layers "F.Cu" "F.Mask" "F.Paste")
			(net "DUT_VDD")
		)
		(pad "2" smd rect
			(at 0 0.9652)
			(size 1.397 1.143)
			(layers "F.Cu" "F.Mask" "F.Paste")
			(net "GND")
		)
	)
	(footprint ""
		(layer "F.Cu")
		(at 63.5254 -86.2838 90)
		(property "Reference" "R480"
			(at 0 0 90)
			(layer "F.SilkS")
			(hide yes)
			(effects
				(font
					(size 1.27 1.27)
				)
			)
		)
		(property "Value" "10KR2F-2-GP"
			(at 0.064008 -3.993896 90)
			(unlocked yes)
			(layer "F.Fab")
			(hide yes)
			(effects
				(font
					(size 1.016 1.016)
					(thickness 0.1524)
				)
			)
		)
		(property "Device Type" "R402H16"
			(at 0.064008 -5.517896 90)
			(unlocked yes)
			(layer "F.Fab")
			(hide yes)
			(effects
				(font
					(size 1.016 1.016)
					(thickness 0.1524)
				)
			)
		)
		(duplicate_pad_numbers_are_jumpers no)
		(fp_line
			(start 0.508 -0.9398)
			(end -0.508 -0.9398)
			(stroke
				(width 0.1524)
				(type default)
			)
			(layer "F.SilkS")
		)
		(fp_line
			(start -0.508 -0.9398)
			(end -0.508 0.9398)
			(stroke
				(width 0.1524)
				(type default)
			)
			(layer "F.SilkS")
		)
		(fp_rect
			(start -0.508 0.9398)
			(end 0.508 -0.9398)
			(stroke
				(width 0)
				(type default)
			)
			(fill no)
			(layer "F.CrtYd")
		)
		(fp_rect
			(start -0.508 0.9398)
			(end 0.508 -0.9398)
			(stroke
				(width 0)
				(type default)
			)
			(fill no)
			(layer "F.Fab")
		)
		(pad "1" smd custom
			(at 0 -0.4445 90)
			(size 0.1397 0.1397)
			(layers "F.Cu" "F.Mask" "F.Paste")
			(net "P3V3_STBY")
			(options
				(clearance outline)
				(anchor circle)
			)
			(primitives
				(gr_poly
					(pts
						(arc
							(start -0.1778 -0.2794)
							(mid -0.249642 -0.249642)
							(end -0.2794 -0.1778)
						)
						(arc
							(start -0.2794 0.1778)
							(mid -0.249642 0.249642)
							(end -0.1778 0.2794)
						)
						(arc
							(start 0.1778 0.2794)
							(mid 0.249642 0.249642)
							(end 0.2794 0.1778)
						)
						(arc
							(start 0.2794 -0.1778)
							(mid 0.249642 -0.249642)
							(end 0.1778 -0.2794)
						)
					)
					(width 0)
					(fill yes)
				)
			)
		)
		(pad "2" smd custom
			(at 0 0.4445 90)
			(size 0.1397 0.1397)
			(layers "F.Cu" "F.Mask" "F.Paste")
			(net "INVERTER_G2")
			(options
				(clearance outline)
				(anchor circle)
			)
			(primitives
				(gr_poly
					(pts
						(arc
							(start -0.1778 -0.2794)
							(mid -0.249642 -0.249642)
							(end -0.2794 -0.1778)
						)
						(arc
							(start -0.2794 0.1778)
							(mid -0.249642 0.249642)
							(end -0.1778 0.2794)
						)
						(arc
							(start 0.1778 0.2794)
							(mid 0.249642 0.249642)
							(end 0.2794 0.1778)
						)
						(arc
							(start 0.2794 -0.1778)
							(mid 0.249642 -0.249642)
							(end 0.1778 -0.2794)
						)
					)
					(width 0)
					(fill yes)
				)
			)
		)
	)
	(footprint ""
		(layer "F.Cu")
		(at 195.3768 -18.796 90)
		(property "Reference" "R566"
			(at 0 0 90)
			(layer "F.SilkS")
			(hide yes)
			(effects
				(font
					(size 1.27 1.27)
				)
			)
		)
		(property "Value" "4K7R2F-GP"
			(at 0.064008 -3.993896 90)
			(unlocked yes)
			(layer "F.Fab")
			(hide yes)
			(effects
				(font
					(size 1.016 1.016)
					(thickness 0.1524)
				)
			)
		)
		(property "Device Type" "R402H16"
			(at 0.064008 -5.517896 90)
			(unlocked yes)
			(layer "F.Fab")
			(hide yes)
			(effects
				(font
					(size 1.016 1.016)
					(thickness 0.1524)
				)
			)
		)
		(duplicate_pad_numbers_are_jumpers no)
		(fp_line
			(start 0.508 -0.9398)
			(end -0.508 -0.9398)
			(stroke
				(width 0.1524)
				(type default)
			)
			(layer "F.SilkS")
		)
		(fp_line
			(start -0.508 -0.9398)
			(end -0.508 0.9398)
			(stroke
				(width 0.1524)
				(type default)
			)
			(layer "F.SilkS")
		)
		(fp_rect
			(start -0.508 0.9398)
			(end 0.508 -0.9398)
			(stroke
				(width 0)
				(type default)
			)
			(fill no)
			(layer "F.CrtYd")
		)
		(fp_rect
			(start -0.508 0.9398)
			(end 0.508 -0.9398)
			(stroke
				(width 0)
				(type default)
			)
			(fill no)
			(layer "F.Fab")
		)
		(pad "1" smd custom
			(at 0 -0.4445 90)
			(size 0.1397 0.1397)
			(layers "F.Cu" "F.Mask" "F.Paste")
			(net "MINISAS_CN15_D_I2C_INT#")
			(options
				(clearance outline)
				(anchor circle)
			)
			(primitives
				(gr_poly
					(pts
						(arc
							(start -0.1778 -0.2794)
							(mid -0.249642 -0.249642)
							(end -0.2794 -0.1778)
						)
						(arc
							(start -0.2794 0.1778)
							(mid -0.249642 0.249642)
							(end -0.1778 0.2794)
						)
						(arc
							(start 0.1778 0.2794)
							(mid 0.249642 0.249642)
							(end 0.2794 0.1778)
						)
						(arc
							(start 0.2794 -0.1778)
							(mid 0.249642 -0.249642)
							(end 0.1778 -0.2794)
						)
					)
					(width 0)
					(fill yes)
				)
			)
		)
		(pad "2" smd custom
			(at 0 0.4445 90)
			(size 0.1397 0.1397)
			(layers "F.Cu" "F.Mask" "F.Paste")
			(net "P3V3_STBY")
			(options
				(clearance outline)
				(anchor circle)
			)
			(primitives
				(gr_poly
					(pts
						(arc
							(start -0.1778 -0.2794)
							(mid -0.249642 -0.249642)
							(end -0.2794 -0.1778)
						)
						(arc
							(start -0.2794 0.1778)
							(mid -0.249642 0.249642)
							(end -0.1778 0.2794)
						)
						(arc
							(start 0.1778 0.2794)
							(mid 0.249642 0.249642)
							(end 0.2794 0.1778)
						)
						(arc
							(start 0.2794 -0.1778)
							(mid 0.249642 -0.249642)
							(end 0.1778 -0.2794)
						)
					)
					(width 0)
					(fill yes)
				)
			)
		)
	)
	(footprint ""
		(layer "F.Cu")
		(at 134.1374 -196.4182)
		(property "Reference" "R9031"
			(at 0 0 0)
			(layer "F.SilkS")
			(hide yes)
			(effects
				(font
					(size 1.27 1.27)
				)
			)
		)
		(property "Value" "4K7R2F-GP"
			(at 0.064008 -3.993896 0)
			(unlocked yes)
			(layer "F.Fab")
			(hide yes)
			(effects
				(font
					(size 1.016 1.016)
					(thickness 0.1524)
				)
			)
		)
		(property "Device Type" "R402H16"
			(at 0.064008 -5.517896 0)
			(unlocked yes)
			(layer "F.Fab")
			(hide yes)
			(effects
				(font
					(size 1.016 1.016)
					(thickness 0.1524)
				)
			)
		)
		(duplicate_pad_numbers_are_jumpers no)
		(fp_line
			(start -0.508 -0.9398)
			(end -0.508 0.9398)
			(stroke
				(width 0.1524)
				(type default)
			)
			(layer "F.SilkS")
		)
		(fp_line
			(start 0.508 -0.9398)
			(end -0.508 -0.9398)
			(stroke
				(width 0.1524)
				(type default)
			)
			(layer "F.SilkS")
		)
		(fp_rect
			(start -0.508 0.9398)
			(end 0.508 -0.9398)
			(stroke
				(width 0)
				(type default)
			)
			(fill no)
			(layer "F.CrtYd")
		)
		(fp_rect
			(start -0.508 0.9398)
			(end 0.508 -0.9398)
			(stroke
				(width 0)
				(type default)
			)
			(fill no)
			(layer "F.Fab")
		)
		(pad "1" smd custom
			(at 0 -0.4445)
			(size 0.1397 0.1397)
			(layers "F.Cu" "F.Mask" "F.Paste")
			(net "SSD_PERST#2")
			(options
				(clearance outline)
				(anchor circle)
			)
			(primitives
				(gr_poly
					(pts
						(arc
							(start -0.1778 -0.2794)
							(mid -0.249642 -0.249642)
							(end -0.2794 -0.1778)
						)
						(arc
							(start -0.2794 0.1778)
							(mid -0.249642 0.249642)
							(end -0.1778 0.2794)
						)
						(arc
							(start 0.1778 0.2794)
							(mid 0.249642 0.249642)
							(end 0.2794 0.1778)
						)
						(arc
							(start 0.2794 -0.1778)
							(mid 0.249642 -0.249642)
							(end 0.1778 -0.2794)
						)
					)
					(width 0)
					(fill yes)
				)
			)
		)
		(pad "2" smd custom
			(at 0 0.4445)
			(size 0.1397 0.1397)
			(layers "F.Cu" "F.Mask" "F.Paste")
			(net "GND")
			(options
				(clearance outline)
				(anchor circle)
			)
			(primitives
				(gr_poly
					(pts
						(arc
							(start -0.1778 -0.2794)
							(mid -0.249642 -0.249642)
							(end -0.2794 -0.1778)
						)
						(arc
							(start -0.2794 0.1778)
							(mid -0.249642 0.249642)
							(end -0.1778 0.2794)
						)
						(arc
							(start 0.1778 0.2794)
							(mid 0.249642 0.249642)
							(end 0.2794 0.1778)
						)
						(arc
							(start 0.2794 -0.1778)
							(mid 0.249642 -0.249642)
							(end 0.1778 -0.2794)
						)
					)
					(width 0)
					(fill yes)
				)
			)
		)
	)
)
